(kicad_pcb
	(version 20260206)
	(generator "pcbnew")
	(generator_version "10.0")
	(general
		(thickness 1.6)
		(legacy_teardrops no)
	)
	(paper "A4")
	(title_block
		(title "01162023_DA0F0TEBIF0_F0T_Expander_BD_F_brd_V02_OCP.brd")
		(comment 1 "Grand Teton / footprints 3337-3343 of 9728")
	)
	(layers
		(0 "F.Cu" signal "TOP")
		(4 "In1.Cu" signal "GND")
		(6 "In2.Cu" signal "VCC")
		(8 "In3.Cu" signal "VCC1")
		(10 "In4.Cu" signal "GND1")
		(12 "In5.Cu" signal "IN1")
		(14 "In6.Cu" signal "GND2")
		(16 "In7.Cu" signal "IN2")
		(18 "In8.Cu" signal "GND3")
		(20 "In9.Cu" signal "IN3")
		(22 "In10.Cu" signal "GND4")
		(24 "In11.Cu" signal "IN4")
		(26 "In12.Cu" signal "GND5")
		(28 "In13.Cu" signal "IN5")
		(30 "In14.Cu" signal "GND6")
		(32 "In15.Cu" signal "IN6")
		(34 "In16.Cu" signal "GND7")
		(2 "B.Cu" signal "BOTTOM")
		(9 "F.Adhes" user "F.Adhesive")
		(11 "B.Adhes" user "B.Adhesive")
		(13 "F.Paste" user "Package Geometry/Pastemask Top")
		(15 "B.Paste" user "Package Geometry/Pastemask Bottom")
		(5 "F.SilkS" user "Ref Des/Silkscreen Top")
		(7 "B.SilkS" user "Ref Des/Silkscreen Bottom")
		(1 "F.Mask" user "Board Geometry/Soldermask Top")
		(3 "B.Mask" user "Board Geometry/Soldermask Bottom")
		(17 "Dwgs.User" user "User.Drawings")
		(19 "Cmts.User" user "User.Comments")
		(21 "Eco1.User" user "User.Eco1")
		(23 "Eco2.User" user "User.Eco2")
		(25 "Edge.Cuts" user "Board Geometry/Outline")
		(27 "Margin" user)
		(31 "F.CrtYd" user "Package Geometry/Place Bound Top")
		(29 "B.CrtYd" user "Package Geometry/Place Bound Bottom")
		(35 "F.Fab" user "Ref Des/Assembly Top")
		(33 "B.Fab" user "Ref Des/Assembly Bottom")
	)
	(footprint ""
		(layer "F.Cu")
		(at 372.642384 -252.356874 -90)
		(property "Reference" "R1434"
			(at 0 0 270)
			(layer "F.SilkS")
			(hide yes)
			(effects
				(font
					(size 1.27 1.27)
				)
			)
		)
		(property "Value" ""
			(at 0 0 270)
			(layer "F.Fab")
			(effects
				(font
					(size 1.27 1.27)
				)
			)
		)
		(duplicate_pad_numbers_are_jumpers no)
		(fp_line
			(start -0.7874 0.4064)
			(end -0.7874 -0.4064)
			(stroke
				(width 0.1524)
				(type default)
			)
			(layer "F.SilkS")
		)
		(fp_line
			(start 0.7874 0.4064)
			(end -0.7874 0.4064)
			(stroke
				(width 0.1524)
				(type default)
			)
			(layer "F.SilkS")
		)
		(fp_line
			(start -0.7874 -0.4064)
			(end 0.7874 -0.4064)
			(stroke
				(width 0.1524)
				(type default)
			)
			(layer "F.SilkS")
		)
		(fp_line
			(start 0.7874 -0.4064)
			(end 0.7874 0.4064)
			(stroke
				(width 0.1524)
				(type default)
			)
			(layer "F.SilkS")
		)
		(fp_line
			(start -0.67945 0.3048)
			(end -0.67945 -0.305054)
			(stroke
				(width 0.1)
				(type default)
			)
			(layer "F.Fab")
		)
		(fp_line
			(start -0.12065 0.3048)
			(end -0.67945 0.3048)
			(stroke
				(width 0.1)
				(type default)
			)
			(layer "F.Fab")
		)
		(fp_line
			(start 0.120396 0.3048)
			(end 0.120396 0.2794)
			(stroke
				(width 0.1)
				(type default)
			)
			(layer "F.Fab")
		)
		(fp_line
			(start 0.67945 0.3048)
			(end 0.120396 0.3048)
			(stroke
				(width 0.1)
				(type default)
			)
			(layer "F.Fab")
		)
		(fp_line
			(start -0.12065 0.2794)
			(end -0.12065 0.3048)
			(stroke
				(width 0.1)
				(type default)
			)
			(layer "F.Fab")
		)
		(fp_line
			(start 0.120396 0.2794)
			(end -0.12065 0.2794)
			(stroke
				(width 0.1)
				(type default)
			)
			(layer "F.Fab")
		)
		(fp_line
			(start -0.12065 -0.2794)
			(end 0.12065 -0.2794)
			(stroke
				(width 0.1)
				(type default)
			)
			(layer "F.Fab")
		)
		(fp_line
			(start 0.12065 -0.2794)
			(end 0.12065 -0.3048)
			(stroke
				(width 0.1)
				(type default)
			)
			(layer "F.Fab")
		)
		(fp_line
			(start 0.12065 -0.3048)
			(end 0.67945 -0.3048)
			(stroke
				(width 0.1)
				(type default)
			)
			(layer "F.Fab")
		)
		(fp_line
			(start 0.67945 -0.3048)
			(end 0.67945 0.3048)
			(stroke
				(width 0.1)
				(type default)
			)
			(layer "F.Fab")
		)
		(fp_line
			(start -0.67945 -0.305054)
			(end -0.12065 -0.305054)
			(stroke
				(width 0.1)
				(type default)
			)
			(layer "F.Fab")
		)
		(fp_line
			(start -0.12065 -0.305054)
			(end -0.12065 -0.2794)
			(stroke
				(width 0.1)
				(type default)
			)
			(layer "F.Fab")
		)
		(pad "1" smd circle
			(at -0.40005 0 270)
			(size 0 0)
			(layers "F.Cu" "F.Mask" "F.Paste")
			(net "GND")
		)
		(pad "2" smd circle
			(at 0.40005 0 270)
			(size 0 0)
			(layers "F.Cu" "F.Mask" "F.Paste")
			(net "PEX3_MODE_SEL9")
		)
	)
	(footprint ""
		(layer "F.Cu")
		(at 476.12427 -528.059142 180)
		(property "Reference" "SCREW_SSD2_2"
			(at -5.207 -1.402334 0)
			(unlocked yes)
			(layer "B.SilkS")
			(effects
				(font
					(size 0.7874 0.5842)
					(thickness 0.1524)
				)
				(justify mirror)
			)
		)
		(property "Value" ""
			(at 0 0 180)
			(layer "F.Fab")
			(effects
				(font
					(size 1.27 1.27)
				)
			)
		)
		(duplicate_pad_numbers_are_jumpers no)
		(pad "1" thru_hole circle
			(at 0 0 180)
			(size 0.4572 0.4572)
			(drill 0.2032)
			(layers "*.Cu" "*.Mask")
			(remove_unused_layers no)
			(net "Net_9139")
			(clearance 0.127)
			(thermal_gap 0.127)
			(padstack
				(mode front_inner_back)
				(layer "Inner"
					(shape circle)
					(size 0.4572 0.4572)
					(clearance 0.127)
				)
				(layer "B.Cu"
					(shape circle)
					(size 0.508 0.508)
					(clearance 0.1016)
				)
			)
		)
	)
	(footprint ""
		(layer "F.Cu")
		(at 29.543756 -311.725564 45)
		(property "Reference" "R1168"
			(at 0 0 45)
			(layer "F.SilkS")
			(hide yes)
			(effects
				(font
					(size 1.27 1.27)
				)
			)
		)
		(property "Value" ""
			(at 0 0 45)
			(layer "F.Fab")
			(effects
				(font
					(size 1.27 1.27)
				)
			)
		)
		(duplicate_pad_numbers_are_jumpers no)
		(fp_line
			(start -0.787389 -0.406267)
			(end 0.787389 -0.406267)
			(stroke
				(width 0.1524)
				(type default)
			)
			(layer "F.SilkS")
		)
		(fp_line
			(start -0.787389 0.406267)
			(end -0.787389 -0.406267)
			(stroke
				(width 0.1524)
				(type default)
			)
			(layer "F.SilkS")
		)
		(fp_line
			(start 0.787389 -0.406267)
			(end 0.787389 0.406267)
			(stroke
				(width 0.1524)
				(type default)
			)
			(layer "F.SilkS")
		)
		(fp_line
			(start 0.787389 0.406267)
			(end -0.787389 0.406267)
			(stroke
				(width 0.1524)
				(type default)
			)
			(layer "F.SilkS")
		)
		(fp_line
			(start -0.679446 -0.305149)
			(end -0.120695 -0.304969)
			(stroke
				(width 0.1)
				(type default)
			)
			(layer "F.Fab")
		)
		(fp_line
			(start -0.120695 -0.304969)
			(end -0.120695 -0.279466)
			(stroke
				(width 0.1)
				(type default)
			)
			(layer "F.Fab")
		)
		(fp_line
			(start -0.120695 -0.279466)
			(end 0.120695 -0.279466)
			(stroke
				(width 0.1)
				(type default)
			)
			(layer "F.Fab")
		)
		(fp_line
			(start -0.679446 0.30479)
			(end -0.679446 -0.305149)
			(stroke
				(width 0.1)
				(type default)
			)
			(layer "F.Fab")
		)
		(fp_line
			(start 0.120515 -0.30479)
			(end 0.679446 -0.30479)
			(stroke
				(width 0.1)
				(type default)
			)
			(layer "F.Fab")
		)
		(fp_line
			(start 0.120695 -0.279466)
			(end 0.120515 -0.30479)
			(stroke
				(width 0.1)
				(type default)
			)
			(layer "F.Fab")
		)
		(fp_line
			(start -0.120695 0.279466)
			(end -0.120515 0.30479)
			(stroke
				(width 0.1)
				(type default)
			)
			(layer "F.Fab")
		)
		(fp_line
			(start -0.120515 0.30479)
			(end -0.679446 0.30479)
			(stroke
				(width 0.1)
				(type default)
			)
			(layer "F.Fab")
		)
		(fp_line
			(start 0.679446 -0.30479)
			(end 0.679446 0.30479)
			(stroke
				(width 0.1)
				(type default)
			)
			(layer "F.Fab")
		)
		(fp_line
			(start 0.120335 0.279466)
			(end -0.120695 0.279466)
			(stroke
				(width 0.1)
				(type default)
			)
			(layer "F.Fab")
		)
		(fp_line
			(start 0.120515 0.30479)
			(end 0.120335 0.279466)
			(stroke
				(width 0.1)
				(type default)
			)
			(layer "F.Fab")
		)
		(fp_line
			(start 0.679446 0.30479)
			(end 0.120515 0.30479)
			(stroke
				(width 0.1)
				(type default)
			)
			(layer "F.Fab")
		)
		(pad "1" smd circle
			(at -0.40005 0 45)
			(size 0 0)
			(layers "F.Cu" "F.Mask" "F.Paste")
			(net "GND")
		)
		(pad "2" smd circle
			(at 0.40005 0 45)
			(size 0 0)
			(layers "F.Cu" "F.Mask" "F.Paste")
			(net "PEX0_DBG_SEL1")
		)
	)
	(footprint ""
		(layer "F.Cu")
		(at 92.071444 -96.811592 -90)
		(property "Reference" "R691"
			(at 0 0 270)
			(layer "F.SilkS")
			(hide yes)
			(effects
				(font
					(size 1.27 1.27)
				)
			)
		)
		(property "Value" ""
			(at 0 0 270)
			(layer "F.Fab")
			(effects
				(font
					(size 1.27 1.27)
				)
			)
		)
		(duplicate_pad_numbers_are_jumpers no)
		(fp_line
			(start -0.7874 0.4064)
			(end -0.7874 -0.4064)
			(stroke
				(width 0.1524)
				(type default)
			)
			(layer "F.SilkS")
		)
		(fp_line
			(start 0.7874 0.4064)
			(end -0.7874 0.4064)
			(stroke
				(width 0.1524)
				(type default)
			)
			(layer "F.SilkS")
		)
		(fp_line
			(start -0.7874 -0.4064)
			(end 0.7874 -0.4064)
			(stroke
				(width 0.1524)
				(type default)
			)
			(layer "F.SilkS")
		)
		(fp_line
			(start 0.7874 -0.4064)
			(end 0.7874 0.4064)
			(stroke
				(width 0.1524)
				(type default)
			)
			(layer "F.SilkS")
		)
		(fp_line
			(start -0.67945 0.3048)
			(end -0.67945 -0.305054)
			(stroke
				(width 0.1)
				(type default)
			)
			(layer "F.Fab")
		)
		(fp_line
			(start -0.12065 0.3048)
			(end -0.67945 0.3048)
			(stroke
				(width 0.1)
				(type default)
			)
			(layer "F.Fab")
		)
		(fp_line
			(start 0.120396 0.3048)
			(end 0.120396 0.2794)
			(stroke
				(width 0.1)
				(type default)
			)
			(layer "F.Fab")
		)
		(fp_line
			(start 0.67945 0.3048)
			(end 0.120396 0.3048)
			(stroke
				(width 0.1)
				(type default)
			)
			(layer "F.Fab")
		)
		(fp_line
			(start -0.12065 0.2794)
			(end -0.12065 0.3048)
			(stroke
				(width 0.1)
				(type default)
			)
			(layer "F.Fab")
		)
		(fp_line
			(start 0.120396 0.2794)
			(end -0.12065 0.2794)
			(stroke
				(width 0.1)
				(type default)
			)
			(layer "F.Fab")
		)
		(fp_line
			(start -0.12065 -0.2794)
			(end 0.12065 -0.2794)
			(stroke
				(width 0.1)
				(type default)
			)
			(layer "F.Fab")
		)
		(fp_line
			(start 0.12065 -0.2794)
			(end 0.12065 -0.3048)
			(stroke
				(width 0.1)
				(type default)
			)
			(layer "F.Fab")
		)
		(fp_line
			(start 0.12065 -0.3048)
			(end 0.67945 -0.3048)
			(stroke
				(width 0.1)
				(type default)
			)
			(layer "F.Fab")
		)
		(fp_line
			(start 0.67945 -0.3048)
			(end 0.67945 0.3048)
			(stroke
				(width 0.1)
				(type default)
			)
			(layer "F.Fab")
		)
		(fp_line
			(start -0.67945 -0.305054)
			(end -0.12065 -0.305054)
			(stroke
				(width 0.1)
				(type default)
			)
			(layer "F.Fab")
		)
		(fp_line
			(start -0.12065 -0.305054)
			(end -0.12065 -0.2794)
			(stroke
				(width 0.1)
				(type default)
			)
			(layer "F.Fab")
		)
		(pad "1" smd circle
			(at -0.40005 0 270)
			(size 0 0)
			(layers "F.Cu" "F.Mask" "F.Paste")
			(net "P3V3_AUX")
		)
		(pad "2" smd circle
			(at 0.40005 0 270)
			(size 0 0)
			(layers "F.Cu" "F.Mask" "F.Paste")
			(net "NIC_ADC_ALERT_N")
		)
	)
	(footprint ""
		(layer "F.Cu")
		(at 338.074 -177.927 180)
		(property "Reference" "R4754"
			(at 0 0 180)
			(layer "F.SilkS")
			(hide yes)
			(effects
				(font
					(size 1.27 1.27)
				)
			)
		)
		(property "Value" ""
			(at 0 0 180)
			(layer "F.Fab")
			(effects
				(font
					(size 1.27 1.27)
				)
			)
		)
		(duplicate_pad_numbers_are_jumpers no)
		(fp_line
			(start 0.7874 0.4064)
			(end -0.7874 0.4064)
			(stroke
				(width 0.1524)
				(type default)
			)
			(layer "F.SilkS")
		)
		(fp_line
			(start 0.7874 -0.4064)
			(end 0.7874 0.4064)
			(stroke
				(width 0.1524)
				(type default)
			)
			(layer "F.SilkS")
		)
		(fp_line
			(start -0.7874 0.4064)
			(end -0.7874 -0.4064)
			(stroke
				(width 0.1524)
				(type default)
			)
			(layer "F.SilkS")
		)
		(fp_line
			(start -0.7874 -0.4064)
			(end 0.7874 -0.4064)
			(stroke
				(width 0.1524)
				(type default)
			)
			(layer "F.SilkS")
		)
		(fp_line
			(start 0.67945 0.3048)
			(end 0.120396 0.3048)
			(stroke
				(width 0.1)
				(type default)
			)
			(layer "F.Fab")
		)
		(fp_line
			(start 0.67945 -0.3048)
			(end 0.67945 0.3048)
			(stroke
				(width 0.1)
				(type default)
			)
			(layer "F.Fab")
		)
		(fp_line
			(start 0.12065 -0.2794)
			(end 0.12065 -0.3048)
			(stroke
				(width 0.1)
				(type default)
			)
			(layer "F.Fab")
		)
		(fp_line
			(start 0.12065 -0.3048)
			(end 0.67945 -0.3048)
			(stroke
				(width 0.1)
				(type default)
			)
			(layer "F.Fab")
		)
		(fp_line
			(start 0.120396 0.3048)
			(end 0.120396 0.2794)
			(stroke
				(width 0.1)
				(type default)
			)
			(layer "F.Fab")
		)
		(fp_line
			(start 0.120396 0.2794)
			(end -0.12065 0.2794)
			(stroke
				(width 0.1)
				(type default)
			)
			(layer "F.Fab")
		)
		(fp_line
			(start -0.12065 0.3048)
			(end -0.67945 0.3048)
			(stroke
				(width 0.1)
				(type default)
			)
			(layer "F.Fab")
		)
		(fp_line
			(start -0.12065 0.2794)
			(end -0.12065 0.3048)
			(stroke
				(width 0.1)
				(type default)
			)
			(layer "F.Fab")
		)
		(fp_line
			(start -0.12065 -0.2794)
			(end 0.12065 -0.2794)
			(stroke
				(width 0.1)
				(type default)
			)
			(layer "F.Fab")
		)
		(fp_line
			(start -0.12065 -0.305054)
			(end -0.12065 -0.2794)
			(stroke
				(width 0.1)
				(type default)
			)
			(layer "F.Fab")
		)
		(fp_line
			(start -0.67945 0.3048)
			(end -0.67945 -0.305054)
			(stroke
				(width 0.1)
				(type default)
			)
			(layer "F.Fab")
		)
		(fp_line
			(start -0.67945 -0.305054)
			(end -0.12065 -0.305054)
			(stroke
				(width 0.1)
				(type default)
			)
			(layer "F.Fab")
		)
		(pad "1" smd circle
			(at -0.40005 0 180)
			(size 0 0)
			(layers "F.Cu" "F.Mask" "F.Paste")
			(net "SSD9_PEX_PWR_EN")
		)
		(pad "2" smd circle
			(at 0.40005 0 180)
			(size 0 0)
			(layers "F.Cu" "F.Mask" "F.Paste")
			(net "SSD9_PEX_PWR_EN_R")
		)
	)
	(footprint ""
		(layer "F.Cu")
		(at 303.446688 -37.47516)
		(property "Reference" "R6099"
			(at 0 0 0)
			(layer "F.SilkS")
			(hide yes)
			(effects
				(font
					(size 1.27 1.27)
				)
			)
		)
		(property "Value" ""
			(at 0 0 0)
			(layer "F.Fab")
			(effects
				(font
					(size 1.27 1.27)
				)
			)
		)
		(duplicate_pad_numbers_are_jumpers no)
		(fp_line
			(start -0.7874 -0.4064)
			(end 0.7874 -0.4064)
			(stroke
				(width 0.1524)
				(type default)
			)
			(layer "F.SilkS")
		)
		(fp_line
			(start -0.7874 0.4064)
			(end -0.7874 -0.4064)
			(stroke
				(width 0.1524)
				(type default)
			)
			(layer "F.SilkS")
		)
		(fp_line
			(start 0.7874 -0.4064)
			(end 0.7874 0.4064)
			(stroke
				(width 0.1524)
				(type default)
			)
			(layer "F.SilkS")
		)
		(fp_line
			(start 0.7874 0.4064)
			(end -0.7874 0.4064)
			(stroke
				(width 0.1524)
				(type default)
			)
			(layer "F.SilkS")
		)
		(fp_line
			(start -0.67945 -0.305054)
			(end -0.12065 -0.305054)
			(stroke
				(width 0.1)
				(type default)
			)
			(layer "F.Fab")
		)
		(fp_line
			(start -0.67945 0.3048)
			(end -0.67945 -0.305054)
			(stroke
				(width 0.1)
				(type default)
			)
			(layer "F.Fab")
		)
		(fp_line
			(start -0.12065 -0.305054)
			(end -0.12065 -0.2794)
			(stroke
				(width 0.1)
				(type default)
			)
			(layer "F.Fab")
		)
		(fp_line
			(start -0.12065 -0.2794)
			(end 0.12065 -0.2794)
			(stroke
				(width 0.1)
				(type default)
			)
			(layer "F.Fab")
		)
		(fp_line
			(start -0.12065 0.2794)
			(end -0.12065 0.3048)
			(stroke
				(width 0.1)
				(type default)
			)
			(layer "F.Fab")
		)
		(fp_line
			(start -0.12065 0.3048)
			(end -0.67945 0.3048)
			(stroke
				(width 0.1)
				(type default)
			)
			(layer "F.Fab")
		)
		(fp_line
			(start 0.120396 0.2794)
			(end -0.12065 0.2794)
			(stroke
				(width 0.1)
				(type default)
			)
			(layer "F.Fab")
		)
		(fp_line
			(start 0.120396 0.3048)
			(end 0.120396 0.2794)
			(stroke
				(width 0.1)
				(type default)
			)
			(layer "F.Fab")
		)
		(fp_line
			(start 0.12065 -0.3048)
			(end 0.67945 -0.3048)
			(stroke
				(width 0.1)
				(type default)
			)
			(layer "F.Fab")
		)
		(fp_line
			(start 0.12065 -0.2794)
			(end 0.12065 -0.3048)
			(stroke
				(width 0.1)
				(type default)
			)
			(layer "F.Fab")
		)
		(fp_line
			(start 0.67945 -0.3048)
			(end 0.67945 0.3048)
			(stroke
				(width 0.1)
				(type default)
			)
			(layer "F.Fab")
		)
		(fp_line
			(start 0.67945 0.3048)
			(end 0.120396 0.3048)
			(stroke
				(width 0.1)
				(type default)
			)
			(layer "F.Fab")
		)
		(pad "1" smd circle
			(at -0.40005 0)
			(size 0 0)
			(layers "F.Cu" "F.Mask" "F.Paste")
			(net "P3V3_SSD11")
		)
		(pad "2" smd circle
			(at 0.40005 0)
			(size 0 0)
			(layers "F.Cu" "F.Mask" "F.Paste")
			(net "P3V3_SSD11_PG_G1")
		)
	)
	(footprint ""
		(layer "F.Cu")
		(at 4.050792 -34.872168 90)
		(property "Reference" "R1641"
			(at 0 0 90)
			(layer "F.SilkS")
			(hide yes)
			(effects
				(font
					(size 1.27 1.27)
				)
			)
		)
		(property "Value" ""
			(at 0 0 90)
			(layer "F.Fab")
			(effects
				(font
					(size 1.27 1.27)
				)
			)
		)
		(duplicate_pad_numbers_are_jumpers no)
		(fp_line
			(start 0.7874 -0.4064)
			(end 0.7874 0.4064)
			(stroke
				(width 0.1524)
				(type default)
			)
			(layer "F.SilkS")
		)
		(fp_line
			(start -0.7874 -0.4064)
			(end 0.7874 -0.4064)
			(stroke
				(width 0.1524)
				(type default)
			)
			(layer "F.SilkS")
		)
		(fp_line
			(start 0.7874 0.4064)
			(end -0.7874 0.4064)
			(stroke
				(width 0.1524)
				(type default)
			)
			(layer "F.SilkS")
		)
		(fp_line
			(start -0.7874 0.4064)
			(end -0.7874 -0.4064)
			(stroke
				(width 0.1524)
				(type default)
			)
			(layer "F.SilkS")
		)
		(fp_line
			(start -0.12065 -0.305054)
			(end -0.12065 -0.2794)
			(stroke
				(width 0.1)
				(type default)
			)
			(layer "F.Fab")
		)
		(fp_line
			(start -0.67945 -0.305054)
			(end -0.12065 -0.305054)
			(stroke
				(width 0.1)
				(type default)
			)
			(layer "F.Fab")
		)
		(fp_line
			(start 0.67945 -0.3048)
			(end 0.67945 0.3048)
			(stroke
				(width 0.1)
				(type default)
			)
			(layer "F.Fab")
		)
		(fp_line
			(start 0.12065 -0.3048)
			(end 0.67945 -0.3048)
			(stroke
				(width 0.1)
				(type default)
			)
			(layer "F.Fab")
		)
		(fp_line
			(start 0.12065 -0.2794)
			(end 0.12065 -0.3048)
			(stroke
				(width 0.1)
				(type default)
			)
			(layer "F.Fab")
		)
		(fp_line
			(start -0.12065 -0.2794)
			(end 0.12065 -0.2794)
			(stroke
				(width 0.1)
				(type default)
			)
			(layer "F.Fab")
		)
		(fp_line
			(start 0.120396 0.2794)
			(end -0.12065 0.2794)
			(stroke
				(width 0.1)
				(type default)
			)
			(layer "F.Fab")
		)
		(fp_line
			(start -0.12065 0.2794)
			(end -0.12065 0.3048)
			(stroke
				(width 0.1)
				(type default)
			)
			(layer "F.Fab")
		)
		(fp_line
			(start 0.67945 0.3048)
			(end 0.120396 0.3048)
			(stroke
				(width 0.1)
				(type default)
			)
			(layer "F.Fab")
		)
		(fp_line
			(start 0.120396 0.3048)
			(end 0.120396 0.2794)
			(stroke
				(width 0.1)
				(type default)
			)
			(layer "F.Fab")
		)
		(fp_line
			(start -0.12065 0.3048)
			(end -0.67945 0.3048)
			(stroke
				(width 0.1)
				(type default)
			)
			(layer "F.Fab")
		)
		(fp_line
			(start -0.67945 0.3048)
			(end -0.67945 -0.305054)
			(stroke
				(width 0.1)
				(type default)
			)
			(layer "F.Fab")
		)
		(pad "1" smd circle
			(at -0.40005 0 90)
			(size 0 0)
			(layers "F.Cu" "F.Mask" "F.Paste")
			(net "SMB_BIC_I2C9_MUX0_SSD0_R_SDA")
		)
		(pad "2" smd circle
			(at 0.40005 0 90)
			(size 0 0)
			(layers "F.Cu" "F.Mask" "F.Paste")
			(net "SMB_ISO_SSD0_SDA")
		)
	)
)
